(kicad_pcb
	(version 20221018)
	(generator pcbnew)
	(general
    (thickness 1.6)
  )
	(paper "A4")
	(title_block
    (title "NUC Computer Cluster Power Breakout HW")
    (date "2023-10-18")
    (rev "1.4.3")
    (company "Antmicro Ltd.")
		(comment 9 "footprints 146-153 of 234")
	)
	(layers
    (0 "F.Cu" mixed)
    (1 "In1.Cu" power)
    (2 "In2.Cu" mixed)
    (31 "B.Cu" power)
    (32 "B.Adhes" user "B.Adhesive")
    (33 "F.Adhes" user "F.Adhesive")
    (34 "B.Paste" user)
    (35 "F.Paste" user)
    (36 "B.SilkS" user "B.Silkscreen")
    (37 "F.SilkS" user "F.Silkscreen")
    (38 "B.Mask" user)
    (39 "F.Mask" user)
    (40 "Dwgs.User" user "User.Drawings")
    (41 "Cmts.User" user "User.Comments")
    (42 "Eco1.User" user "User.Eco1")
    (43 "Eco2.User" user "User.Eco2")
    (44 "Edge.Cuts" user)
    (45 "Margin" user)
    (46 "B.CrtYd" user "B.Courtyard")
    (47 "F.CrtYd" user "F.Courtyard")
    (48 "B.Fab" user)
    (49 "F.Fab" user)
  )
	(footprint "antmicro-footprints:TP_SMD_1mm" (layer "F.Cu")
    (at 111.65 137.4 -90)
    (property "Author" "Antmicro")
    (property "License" "Apache-2.0")
    (property "MPN" "")
    (property "Manufacturer" "")
    (property "Sheetfile" "d1600e-psu-breakout-board.kicad_sch")
    (property "Sheetname" "")
    (property "exclude_from_bom" "")
    (property "ki_description" "Test point 1mm SMD")
    (property "ki_keywords" "TESTPOINT")
    (attr exclude_from_pos_files exclude_from_bom)
    (fp_text reference "TP_S10" (at -0.45 -0.4 -90) (layer "F.SilkS")
        (effects (font (size 0.7 0.7) (thickness 0.15)) (justify left bottom))
    )
    (fp_text value "TP_1mm_SMD" (at 0 1.4 -90) (layer "F.Fab")
        (effects (font (size 0.7 0.7) (thickness 0.15)) (justify left bottom))
    )
    (fp_text user "${REFERENCE}" (at -0.5 2.8 -90) (layer "F.Fab") hide
        (effects (font (size 0.7 0.7) (thickness 0.15)) (justify left bottom))
    )
    (fp_text user "Author: Antmicro" (at -0.5 4 -90) (layer "F.Fab") hide
        (effects (font (size 0.7 0.7) (thickness 0.15)) (justify left bottom))
    )
    (fp_text user "License: Apache-2.0" (at -0.5 5.2 -90) (layer "F.Fab") hide
        (effects (font (size 0.7 0.7) (thickness 0.15)) (justify left bottom))
    )
    (fp_circle (center 0 0) (end 0.6 0)
      (stroke (width 0.05) (type default)) (fill none) (layer "F.CrtYd"))
    (pad "1" smd circle (at 0 0 270) (size 1 1) (layers "F.Cu" "F.Mask")
      (net 58 "Net-(J10-PadS10)") (pinfunction "1") (pintype "passive"))
  )
	(footprint "antmicro-footprints:TP_SMD_1mm" (layer "F.Cu")
    (at 113.05 137.4 -90)
    (property "Author" "Antmicro")
    (property "License" "Apache-2.0")
    (property "MPN" "")
    (property "Manufacturer" "")
    (property "Sheetfile" "d1600e-psu-breakout-board.kicad_sch")
    (property "Sheetname" "")
    (property "exclude_from_bom" "")
    (property "ki_description" "Test point 1mm SMD")
    (property "ki_keywords" "TESTPOINT")
    (attr exclude_from_pos_files exclude_from_bom)
    (fp_text reference "TP_S9" (at -0.745801 -0.314513 -90) (layer "F.SilkS")
        (effects (font (size 0.7 0.7) (thickness 0.15)) (justify left bottom))
    )
    (fp_text value "TP_1mm_SMD" (at 0 1.4 -90) (layer "F.Fab")
        (effects (font (size 0.7 0.7) (thickness 0.15)) (justify left bottom))
    )
    (fp_text user "${REFERENCE}" (at -0.5 2.8 -90) (layer "F.Fab") hide
        (effects (font (size 0.7 0.7) (thickness 0.15)) (justify left bottom))
    )
    (fp_text user "Author: Antmicro" (at -0.5 4 -90) (layer "F.Fab") hide
        (effects (font (size 0.7 0.7) (thickness 0.15)) (justify left bottom))
    )
    (fp_text user "License: Apache-2.0" (at -0.5 5.2 -90) (layer "F.Fab") hide
        (effects (font (size 0.7 0.7) (thickness 0.15)) (justify left bottom))
    )
    (fp_circle (center 0 0) (end 0.6 0)
      (stroke (width 0.05) (type default)) (fill none) (layer "F.CrtYd"))
    (pad "1" smd circle (at 0 0 270) (size 1 1) (layers "F.Cu" "F.Mask")
      (net 59 "Net-(J10-PadS9)") (pinfunction "1") (pintype "passive"))
  )
	(footprint "antmicro-footprints:R_0402_1005Metric" (layer "F.Cu")
    (at 177.35 92)
    (descr "Resistor SMD 0402")
    (tags "resistor SMD 0402")
    (property "Author" "Antmicro")
    (property "DNP" "DNP")
    (property "License" "Apache-2.0")
    (property "MPN" "CR0402-FX-1002GLF")
    (property "Manufacturer" "Bourns")
    (property "Sheetfile" "power-switch.kicad_sch")
    (property "Sheetname" "Power switch 5")
    (property "Tolerance" "1%")
    (property "Val" "10k")
    (property "dnp" "")
    (property "exclude_from_bom" "")
    (property "ki_description" "SMD Chip Resistor, 10 kohm, ± 1%, 62.5 mW, 0402 [1005 Metric], Thick Film, General Purpose")
    (property "ki_keywords" "0402, SMT, RESISTOR, PASSIVE")
    (attr smd exclude_from_bom)
    (fp_text reference "R48" (at -0.05 1.05) (layer "F.SilkS")
        (effects (font (size 0.7 0.7) (thickness 0.15)))
    )
    (fp_text value "R_10k_0402" (at 0 1.17) (layer "F.Fab") hide
        (effects (font (size 1 1) (thickness 0.15)))
    )
    (fp_text user "Author: Antmicro" (at -0.95 4.169) (layer "F.Fab") hide
        (effects (font (size 0.7 0.7) (thickness 0.15)) (justify left bottom))
    )
    (fp_text user "${REFERENCE}" (at 0 0) (layer "F.Fab")
        (effects (font (size 0.25 0.25) (thickness 0.04)))
    )
    (fp_text user "License: Apache-2.0" (at -0.95 5.169) (layer "F.Fab") hide
        (effects (font (size 0.7 0.7) (thickness 0.15)) (justify left bottom))
    )
    (fp_rect (start -0.925 -0.47) (end 0.925 0.47)
      (stroke (width 0.05) (type default)) (fill none) (layer "F.CrtYd"))
    (fp_rect (start -0.5 -0.25) (end 0.5 0.25)
      (stroke (width 0.15) (type solid)) (fill none) (layer "F.Fab"))
    (pad "1" smd roundrect (at -0.48 0) (size 0.59 0.64) (layers "F.Cu" "F.Paste" "F.Mask") (roundrect_rratio 0.25)
      (net 26 "/Power Cycling & Current Measurement/PC_5") (pintype "passive"))
    (pad "2" smd roundrect (at 0.48 0) (size 0.59 0.64) (layers "F.Cu" "F.Paste" "F.Mask") (roundrect_rratio 0.25)
      (net 4 "GND") (pintype "passive"))
  )
	(footprint "antmicro-footprints:Conn_Molex_KK_1x4_22-27-2041" (layer "F.Cu")
    (at 99.91 54.15)
    (property "Author" "Antmicro")
    (property "License" "Apache-2.0")
    (property "MPN" "22-27-2041")
    (property "Manufacturer" "Molex")
    (property "Sheetfile" "d1600e-psu-breakout-board.kicad_sch")
    (property "Sheetname" "")
    (property "ki_description" "Rectangular connector (header, female pins)")
    (property "ki_keywords" "VERTICAL, THT, HEADER, CONNECTOR, MALE")
    (attr through_hole)
    (fp_text reference "J1" (at 2.165 4.3) (layer "F.SilkS")
        (effects (font (size 0.7 0.7) (thickness 0.15)) (justify left bottom))
    )
    (fp_text value "Molex_KK_1x4_22-27-2041" (at -0.8 4.6 180) (layer "F.Fab")
        (effects (font (size 0.7 0.7) (thickness 0.15)) (justify left bottom))
    )
    (fp_text user "${REFERENCE}" (at -2.12 9.15) (layer "F.Fab") hide
        (effects (font (size 0.7 0.7) (thickness 0.15)) (justify left bottom))
    )
    (fp_text user "Author: Antmicro" (at -2.12 6.75) (layer "F.Fab") hide
        (effects (font (size 0.7 0.7) (thickness 0.15)) (justify left bottom))
    )
    (fp_text user "License: Apache-2.0" (at -2.12 7.95) (layer "F.Fab") hide
        (effects (font (size 0.7 0.7) (thickness 0.15)) (justify left bottom))
    )
    (fp_line (start -1.39 -3.03) (end -1.39 2.99)
      (stroke (width 0.15) (type solid)) (layer "F.SilkS"))
    (fp_line (start -1.39 2.99) (end 8.99 2.99)
      (stroke (width 0.15) (type solid)) (layer "F.SilkS"))
    (fp_line (start -0.81 -3.03) (end -0.81 -2.43)
      (stroke (width 0.15) (type solid)) (layer "F.SilkS"))
    (fp_line (start -0.81 -2.43) (end 0.79 -2.43)
      (stroke (width 0.15) (type solid)) (layer "F.SilkS"))
    (fp_line (start -0.01 1.99) (end 0.24 1.46)
      (stroke (width 0.15) (type solid)) (layer "F.SilkS"))
    (fp_line (start -0.01 1.99) (end 7.61 1.99)
      (stroke (width 0.15) (type solid)) (layer "F.SilkS"))
    (fp_line (start -0.01 2.99) (end -0.01 1.99)
      (stroke (width 0.15) (type solid)) (layer "F.SilkS"))
    (fp_line (start 0.24 1.46) (end 7.36 1.46)
      (stroke (width 0.15) (type solid)) (layer "F.SilkS"))
    (fp_line (start 0.24 2.99) (end 0.24 1.99)
      (stroke (width 0.15) (type solid)) (layer "F.SilkS"))
    (fp_line (start 0.79 -2.43) (end 0.79 -3.03)
      (stroke (width 0.15) (type solid)) (layer "F.SilkS"))
    (fp_line (start 1.73 -3.03) (end 1.73 -2.43)
      (stroke (width 0.15) (type solid)) (layer "F.SilkS"))
    (fp_line (start 1.73 -2.43) (end 3.33 -2.43)
      (stroke (width 0.15) (type solid)) (layer "F.SilkS"))
    (fp_line (start 3.33 -2.43) (end 3.33 -3.03)
      (stroke (width 0.15) (type solid)) (layer "F.SilkS"))
    (fp_line (start 4.27 -3.03) (end 4.27 -2.43)
      (stroke (width 0.15) (type solid)) (layer "F.SilkS"))
    (fp_line (start 4.27 -2.43) (end 5.87 -2.43)
      (stroke (width 0.15) (type solid)) (layer "F.SilkS"))
    (fp_line (start 5.87 -2.43) (end 5.87 -3.03)
      (stroke (width 0.15) (type solid)) (layer "F.SilkS"))
    (fp_line (start 6.81 -3.03) (end 6.81 -2.43)
      (stroke (width 0.15) (type solid)) (layer "F.SilkS"))
    (fp_line (start 6.81 -2.43) (end 8.41 -2.43)
      (stroke (width 0.15) (type solid)) (layer "F.SilkS"))
    (fp_line (start 7.36 1.46) (end 7.61 1.99)
      (stroke (width 0.15) (type solid)) (layer "F.SilkS"))
    (fp_line (start 7.36 2.99) (end 7.36 1.99)
      (stroke (width 0.15) (type solid)) (layer "F.SilkS"))
    (fp_line (start 7.61 1.99) (end 7.61 2.99)
      (stroke (width 0.15) (type solid)) (layer "F.SilkS"))
    (fp_line (start 8.41 -2.43) (end 8.41 -3.03)
      (stroke (width 0.15) (type solid)) (layer "F.SilkS"))
    (fp_line (start 8.99 -3.03) (end -1.39 -3.03)
      (stroke (width 0.15) (type solid)) (layer "F.SilkS"))
    (fp_line (start 8.99 2.99) (end 8.99 -3.03)
      (stroke (width 0.15) (type solid)) (layer "F.SilkS"))
    (fp_line (start -1.79 -3.38) (end -1.79 3.42)
      (stroke (width 0.05) (type solid)) (layer "F.CrtYd"))
    (fp_line (start -1.79 3.42) (end 9.37 3.42)
      (stroke (width 0.05) (type solid)) (layer "F.CrtYd"))
    (fp_line (start 9.37 -3.38) (end -1.79 -3.38)
      (stroke (width 0.05) (type solid)) (layer "F.CrtYd"))
    (fp_line (start 9.37 3.42) (end 9.37 -3.38)
      (stroke (width 0.05) (type solid)) (layer "F.CrtYd"))
    (fp_line (start -1.29 -2.88) (end -1.29 2.92)
      (stroke (width 0.15) (type solid)) (layer "F.Fab"))
    (fp_line (start -1.29 2.92) (end 8.87 2.92)
      (stroke (width 0.15) (type solid)) (layer "F.Fab"))
    (fp_line (start 8.163 0) (end 8.87 -0.5)
      (stroke (width 0.15) (type solid)) (layer "F.Fab"))
    (fp_line (start 8.87 -2.88) (end -1.29 -2.88)
      (stroke (width 0.15) (type solid)) (layer "F.Fab"))
    (fp_line (start 8.87 0.5) (end 8.163 0)
      (stroke (width 0.15) (type solid)) (layer "F.Fab"))
    (fp_line (start 8.87 2.92) (end 8.87 -2.88)
      (stroke (width 0.15) (type solid)) (layer "F.Fab"))
    (pad "1" thru_hole roundrect (at 0 0) (size 1.74 2.19) (drill 1.19) (layers "*.Cu" "*.Mask") (roundrect_rratio 0.143678)
      (net 11 "VCC12V0") (pintype "passive"))
    (pad "2" thru_hole oval (at 2.54 0) (size 1.74 2.19) (drill 1.19) (layers "*.Cu" "*.Mask")
      (net 4 "GND") (pintype "passive"))
    (pad "3" thru_hole oval (at 5.08 0) (size 1.74 2.19) (drill 1.19) (layers "*.Cu" "*.Mask")
      (net 4 "GND") (pintype "passive"))
    (pad "4" thru_hole oval (at 7.62 0) (size 1.74 2.19) (drill 1.19) (layers "*.Cu" "*.Mask")
      (net 2 "VCC5V0") (pintype "passive"))
  )
	(footprint "antmicro-footprints:R_0402_1005Metric" (layer "F.Cu")
    (at 179.85 100.12)
    (descr "Resistor SMD 0402")
    (tags "resistor SMD 0402")
    (property "Author" "Antmicro")
    (property "Current" "1A")
    (property "DNP" "DNP")
    (property "License" "Apache-2.0")
    (property "MPN" "ERJ2GE0R00X")
    (property "Manufacturer" "Panasonic")
    (property "Sheetfile" "d1600e-psu-breakout-board.kicad_sch")
    (property "Sheetname" "")
    (property "Tolerance" "")
    (property "Val" "0R")
    (property "dnp" "")
    (property "exclude_from_bom" "")
    (property "ki_description" "SMD Chip Resistor, Jumper, 0 ohm, 100 mW, 0402 [1005 Metric], Thick Film, General Purpose")
    (property "ki_keywords" "0402, SMT, RESISTOR, PASSIVE")
    (attr smd exclude_from_bom)
    (fp_text reference "R71" (at -1.122484 -0.772697) (layer "F.SilkS")
        (effects (font (size 0.7 0.7) (thickness 0.15)) (justify left bottom))
    )
    (fp_text value "R_0R_0402" (at -1.011843 1.772047) (layer "F.Fab")
        (effects (font (size 0.7 0.7) (thickness 0.15)) (justify left bottom))
    )
    (fp_text user "License: Apache-2.0" (at -0.95 5.169) (layer "F.Fab") hide
        (effects (font (size 0.7 0.7) (thickness 0.15)) (justify left bottom))
    )
    (fp_text user "Author: Antmicro" (at -0.95 4.169) (layer "F.Fab") hide
        (effects (font (size 0.7 0.7) (thickness 0.15)) (justify left bottom))
    )
    (fp_text user "${REFERENCE}" (at -0.95 3.168) (layer "F.Fab") hide
        (effects (font (size 0.7 0.7) (thickness 0.15)) (justify left bottom))
    )
    (fp_rect (start -0.925 -0.47) (end 0.925 0.47)
      (stroke (width 0.05) (type default)) (fill none) (layer "F.CrtYd"))
    (fp_rect (start -0.5 -0.25) (end 0.5 0.25)
      (stroke (width 0.15) (type solid)) (fill none) (layer "F.Fab"))
    (pad "1" smd roundrect (at -0.48 0) (size 0.59 0.64) (layers "F.Cu" "F.Paste" "F.Mask") (roundrect_rratio 0.25)
      (net 18 "SDA") (pintype "passive"))
    (pad "2" smd roundrect (at 0.48 0) (size 0.59 0.64) (layers "F.Cu" "F.Paste" "F.Mask") (roundrect_rratio 0.25)
      (net 99 "SDA_CON") (pintype "passive"))
  )
	(footprint "antmicro-footprints:R_0603_1608Metric" (layer "F.Cu")
    (at 148.7 53.85)
    (descr "Resistor SMD 0603")
    (tags "resistor SMD 0603")
    (property "Author" "Antmicro")
    (property "License" "Apache-2.0")
    (property "MPN" "CR0603-FX-4701ELF")
    (property "Manufacturer" "Bourns")
    (property "Sheetfile" "d1600e-psu-breakout-board.kicad_sch")
    (property "Sheetname" "")
    (property "Tolerance" "1%")
    (property "Val" "4k7")
    (property "ki_description" "SMD Chip Resistor, 4.7 kohm, ± 1%, 100 mW, 0603 [1608 Metric], Thick Film, General Purpose")
    (property "ki_keywords" "0603, SMT, RESISTOR, PASSIVE")
    (attr smd)
    (fp_text reference "R51" (at -1.1 1.65) (layer "F.SilkS")
        (effects (font (size 0.7 0.7) (thickness 0.15)) (justify left bottom))
    )
    (fp_text value "R_4k7_0603" (at 0 1.6) (layer "F.Fab")
        (effects (font (size 0.7 0.7) (thickness 0.15)) (justify left bottom))
    )
    (fp_text user "License: Apache-2.0" (at -1.25 5.9) (layer "F.Fab") hide
        (effects (font (size 0.7 0.7) (thickness 0.15)) (justify left bottom))
    )
    (fp_text user "${REFERENCE}" (at -1.25 3.898) (layer "F.Fab") hide
        (effects (font (size 0.7 0.7) (thickness 0.15)) (justify left bottom))
    )
    (fp_text user "Author: Antmicro" (at -1.25 4.9) (layer "F.Fab") hide
        (effects (font (size 0.7 0.7) (thickness 0.15)) (justify left bottom))
    )
    (fp_line (start -0.15 -0.4) (end 0.15 -0.4)
      (stroke (width 0.15) (type solid)) (layer "F.SilkS"))
    (fp_line (start -0.15 0.4) (end 0.15 0.4)
      (stroke (width 0.15) (type solid)) (layer "F.SilkS"))
    (fp_rect (start -1.25 -0.65) (end 1.25 0.65)
      (stroke (width 0.05) (type solid)) (fill none) (layer "F.CrtYd"))
    (fp_rect (start -0.8 -0.4) (end 0.8 0.4)
      (stroke (width 0.15) (type solid)) (fill none) (layer "F.Fab"))
    (pad "1" smd roundrect (at -0.7 0) (size 0.8 1) (layers "F.Cu" "F.Paste" "F.Mask") (roundrect_rratio 0.2)
      (net 40 "Net-(D6-A)") (pintype "passive"))
    (pad "2" smd roundrect (at 0.7 0) (size 0.8 1) (layers "F.Cu" "F.Paste" "F.Mask") (roundrect_rratio 0.2)
      (net 42 "LOAD_3") (pintype "passive"))
  )
	(footprint "antmicro-footprints:R_0402_1005Metric" (layer "F.Cu")
    (at 167.65 113.5 90)
    (descr "Resistor SMD 0402")
    (tags "resistor SMD 0402")
    (property "Author" "Antmicro")
    (property "License" "Apache-2.0")
    (property "MPN" "CR0402-FX-4701GLF")
    (property "Manufacturer" "Bourns")
    (property "Sheetfile" "ftdi-module.kicad_sch")
    (property "Sheetname" "FTDI")
    (property "Tolerance" "1%")
    (property "Val" "4k7")
    (property "ki_description" "SMD Chip Resistor, 4.7 kohm, ± 1%, 62.5 mW, 0402 [1005 Metric], Thick Film, General Purpose")
    (property "ki_keywords" "0402, SMT, RESISTOR, PASSIVE")
    (attr smd)
    (fp_text reference "R5" (at 0.9 0.45 90) (layer "F.SilkS")
        (effects (font (size 0.7 0.7) (thickness 0.15)) (justify left bottom))
    )
    (fp_text value "R_4k7_0402" (at -1.011843 1.772047 90) (layer "F.Fab")
        (effects (font (size 0.7 0.7) (thickness 0.15)) (justify left bottom))
    )
    (fp_text user "Author: Antmicro" (at -0.95 4.169 90) (layer "F.Fab") hide
        (effects (font (size 0.7 0.7) (thickness 0.15)) (justify left bottom))
    )
    (fp_text user "License: Apache-2.0" (at -0.95 5.169 90) (layer "F.Fab") hide
        (effects (font (size 0.7 0.7) (thickness 0.15)) (justify left bottom))
    )
    (fp_text user "${REFERENCE}" (at -0.95 3.168 90) (layer "F.Fab") hide
        (effects (font (size 0.7 0.7) (thickness 0.15)) (justify left bottom))
    )
    (fp_rect (start -0.925 -0.47) (end 0.925 0.47)
      (stroke (width 0.05) (type default)) (fill none) (layer "F.CrtYd"))
    (fp_rect (start -0.5 -0.25) (end 0.5 0.25)
      (stroke (width 0.15) (type solid)) (fill none) (layer "F.Fab"))
    (pad "1" smd roundrect (at -0.48 0 90) (size 0.59 0.64) (layers "F.Cu" "F.Paste" "F.Mask") (roundrect_rratio 0.25)
      (net 81 "SCL_FTDI") (pintype "passive"))
    (pad "2" smd roundrect (at 0.48 0 90) (size 0.59 0.64) (layers "F.Cu" "F.Paste" "F.Mask") (roundrect_rratio 0.25)
      (net 76 "VCC3V3_USB") (pintype "passive"))
  )
	(footprint "antmicro-footprints:R_0603_1608Metric" (layer "F.Cu")
    (at 164.5 106.3 90)
    (descr "Resistor SMD 0603")
    (tags "resistor SMD 0603")
    (property "Author" "Antmicro")
    (property "Current" "1A")
    (property "DNP" "DNP")
    (property "License" "Apache-2.0")
    (property "MPN" "CR0603-J/-000ELF")
    (property "Manufacturer" "Bourns")
    (property "Sheetfile" "ftdi-module.kicad_sch")
    (property "Sheetname" "FTDI")
    (property "Tolerance" "")
    (property "Val" "0R")
    (property "dnp" "")
    (property "exclude_from_bom" "")
    (property "ki_description" "Zero Ohm Resistor, Jumper, 0603 [1608 Metric], Thick Film, 100 mW, 1 A, Surface Mount Device, CR")
    (property "ki_keywords" "0603, SMT, RESISTOR, PASSIVE")
    (attr smd exclude_from_bom)
    (fp_text reference "R75" (at 0 -1.2 90) (layer "F.SilkS")
        (effects (font (size 0.7 0.7) (thickness 0.15)))
    )
    (fp_text value "R_0R_0603" (at 0 1.9 90) (layer "F.Fab")
        (effects (font (size 1 1) (thickness 0.15)))
    )
    (fp_text user "${REFERENCE}" (at -1.25 3.898 90) (layer "F.Fab") hide
        (effects (font (size 0.7 0.7) (thickness 0.15)) (justify left bottom))
    )
    (fp_text user "License: Apache-2.0" (at -1.25 5.9 90) (layer "F.Fab") hide
        (effects (font (size 0.7 0.7) (thickness 0.15)) (justify left bottom))
    )
    (fp_text user "Author: Antmicro" (at -1.25 4.9 90) (layer "F.Fab") hide
        (effects (font (size 0.7 0.7) (thickness 0.15)) (justify left bottom))
    )
    (fp_line (start -0.15 -0.4) (end 0.15 -0.4)
      (stroke (width 0.15) (type solid)) (layer "F.SilkS"))
    (fp_line (start -0.15 0.4) (end 0.15 0.4)
      (stroke (width 0.15) (type solid)) (layer "F.SilkS"))
    (fp_rect (start -1.25 -0.65) (end 1.25 0.65)
      (stroke (width 0.05) (type solid)) (fill none) (layer "F.CrtYd"))
    (fp_rect (start -0.8 -0.4) (end 0.8 0.4)
      (stroke (width 0.15) (type solid)) (fill none) (layer "F.Fab"))
    (pad "1" smd roundrect (at -0.7 0 90) (size 0.8 1) (layers "F.Cu" "F.Paste" "F.Mask") (roundrect_rratio 0.2)
      (net 116 "Net-(U5-BDBUS1)") (pintype "passive"))
    (pad "2" smd roundrect (at 0.7 0 90) (size 0.8 1) (layers "F.Cu" "F.Paste" "F.Mask") (roundrect_rratio 0.2)
      (net 145 "LED_DATA") (pintype "passive"))
  )
)
